# BASEBOARD_FAB2 (Tioga Pass) — schematic netlist excerpt (pin names and nets, part order shuffled) for the footprints in the layout excerpt that follows; sources: Cadence DE-HDL packaged netlist, KiCad conversion of Wiwynn_Tioga_Pass_MB.brd

R1T28  RES  49.9 1% CHIP  pkg 0402  page 151 : A = BMC_M_CLK_DN ; B = BMC_M_CLK
R2T57  RES  0.0 5% EMPTY  pkg 0402  page 93 : A = H_CPU_ERR0_PCH_N ; B = H_CPU_ERR0_GTL_R_N
C25W58  CAP_A  0.1UF 16V 10% X7R  pkg 0402V  page 149 : A = VCC_PA_3V3 ; B = GND

(kicad_pcb
	(version 20260206)
	(generator "pcbnew")
	(generator_version "10.0")
	(general
		(thickness 1.6)
		(legacy_teardrops no)
	)
	(paper "A4")
	(title_block
		(title "Wiwynn_Tioga_Pass_MB.brd")
		(comment 1 "Tioga Pass / footprints 4309-4311 of 4770")
	)
	(layers
		(0 "F.Cu" signal "TOP")
		(4 "In1.Cu" signal "L2GND")
		(6 "In2.Cu" signal "L3")
		(8 "In3.Cu" signal "L4GND")
		(10 "In4.Cu" signal "L5")
		(12 "In5.Cu" signal "L6GND")
		(14 "In6.Cu" signal "L7VCC")
		(16 "In7.Cu" signal "L8VCC")
		(18 "In8.Cu" signal "L9GND")
		(20 "In9.Cu" signal "L10")
		(22 "In10.Cu" signal "L11GND")
		(24 "In11.Cu" signal "L12")
		(26 "In12.Cu" signal "L13GND")
		(2 "B.Cu" signal "BOTTOM")
		(9 "F.Adhes" user "F.Adhesive")
		(11 "B.Adhes" user "B.Adhesive")
		(13 "F.Paste" user "Package Geometry/Pastemask Top")
		(15 "B.Paste" user "Package Geometry/Pastemask Bottom")
		(5 "F.SilkS" user "Ref Des/Silkscreen Top")
		(7 "B.SilkS" user "Ref Des/Silkscreen Bottom")
		(1 "F.Mask" user "Board Geometry/Soldermask Top")
		(3 "B.Mask" user "Board Geometry/Soldermask Bottom")
		(17 "Dwgs.User" user "User.Drawings")
		(19 "Cmts.User" user "User.Comments")
		(21 "Eco1.User" user "User.Eco1")
		(23 "Eco2.User" user "User.Eco2")
		(25 "Edge.Cuts" user "Board Geometry/Outline")
		(27 "Margin" user)
		(31 "F.CrtYd" user "Package Geometry/Place Bound Top")
		(29 "B.CrtYd" user "Package Geometry/Place Bound Bottom")
		(35 "F.Fab" user "Ref Des/Assembly Top")
		(33 "B.Fab" user "Ref Des/Assembly Bottom")
	)
	(footprint ""
		(layer "B.Cu")
		(at 438.604406 -33.101026 90)
		(property "Reference" "R1T28"
			(at 0.8382 -0.67818 90)
			(unlocked yes)
			(layer "B.SilkS")
			(effects
				(font
					(size 0.4064 0.254)
					(thickness 0.1524)
				)
				(justify left mirror)
			)
		)
		(property "Value" ""
			(at 0 0 90)
			(layer "B.Fab")
			(effects
				(font
					(size 1.27 1.27)
				)
				(justify mirror)
			)
		)
		(duplicate_pad_numbers_are_jumpers no)
		(fp_poly
			(pts
				(xy 0.2794 -0.1016) (xy -0.2794 -0.1016) (xy -0.2794 0.9906) (xy 0.2794 0.9906)
			)
			(stroke
				(width 0)
				(type default)
			)
			(fill no)
			(layer "B.CrtYd")
		)
		(fp_line
			(start 0.2794 -0.1016)
			(end 0.2794 0.9906)
			(stroke
				(width 0.1)
				(type default)
			)
			(layer "B.Fab")
		)
		(fp_line
			(start -0.2794 -0.1016)
			(end 0.2794 -0.1016)
			(stroke
				(width 0.1)
				(type default)
			)
			(layer "B.Fab")
		)
		(fp_line
			(start 0.2794 0.9906)
			(end -0.2794 0.9906)
			(stroke
				(width 0.1)
				(type default)
			)
			(layer "B.Fab")
		)
		(fp_line
			(start -0.2794 0.9906)
			(end -0.2794 -0.1016)
			(stroke
				(width 0.1)
				(type default)
			)
			(layer "B.Fab")
		)
		(pad "1" smd rect
			(at 0 0 270)
			(size 0.508 0.508)
			(layers "B.Cu" "B.Mask" "B.Paste")
			(net "BMC_M_CLK_DN")
		)
		(pad "2" smd rect
			(at 0 0.889 270)
			(size 0.508 0.508)
			(layers "B.Cu" "B.Mask" "B.Paste")
			(net "BMC_M_CLK")
		)
		(zone
			(layer "B.Cu")
			(hatch none 0.5)
			(connect_pads
				(clearance 0)
			)
			(min_thickness 0.25)
			(keepout
				(tracks allowed)
				(vias not_allowed)
				(pads allowed)
				(copperpour not_allowed)
				(footprints allowed)
			)
			(placement
				(enabled no)
				(sheetname "")
			)
			(fill
				(thermal_gap 0.5)
				(thermal_bridge_width 0.5)
				(island_removal_mode 0)
			)
			(polygon
				(pts
					(xy 438.858406 -33.355026) (xy 438.858406 -32.847026) (xy 439.239406 -32.847026) (xy 439.239406 -33.355026)
				)
			)
		)
		(zone
			(layer "B.Cu")
			(hatch none 0.5)
			(connect_pads
				(clearance 0)
			)
			(min_thickness 0.25)
			(keepout
				(tracks not_allowed)
				(vias allowed)
				(pads allowed)
				(copperpour not_allowed)
				(footprints allowed)
			)
			(placement
				(enabled no)
				(sheetname "")
			)
			(fill
				(thermal_gap 0.5)
				(thermal_bridge_width 0.5)
				(island_removal_mode 0)
			)
			(polygon
				(pts
					(xy 439.239406 -33.355026) (xy 439.239406 -32.847026) (xy 438.858406 -32.847026) (xy 438.858406 -33.355026)
				)
			)
		)
	)
	(footprint ""
		(layer "B.Cu")
		(at 423.387774 -40.982646 180)
		(property "Reference" "C25W58"
			(at 0.8382 -0.67818 180)
			(unlocked yes)
			(layer "B.SilkS")
			(effects
				(font
					(size 0.4064 0.254)
					(thickness 0.1524)
				)
				(justify left mirror)
			)
		)
		(property "Value" ""
			(at 0 0 0)
			(layer "B.Fab")
			(effects
				(font
					(size 1.27 1.27)
				)
				(justify mirror)
			)
		)
		(duplicate_pad_numbers_are_jumpers no)
		(fp_poly
			(pts
				(xy -0.3048 -0.1016) (xy -0.3048 0.9906) (xy 0.3048 0.9906) (xy 0.3048 -0.1016)
			)
			(stroke
				(width 0)
				(type default)
			)
			(fill no)
			(layer "B.CrtYd")
		)
		(fp_line
			(start 0.3048 0.9906)
			(end -0.3048 0.9906)
			(stroke
				(width 0.1)
				(type default)
			)
			(layer "B.Fab")
		)
		(fp_line
			(start 0.3048 -0.1016)
			(end 0.3048 0.9906)
			(stroke
				(width 0.1)
				(type default)
			)
			(layer "B.Fab")
		)
		(fp_line
			(start -0.3048 0.9906)
			(end -0.3048 -0.1016)
			(stroke
				(width 0.1)
				(type default)
			)
			(layer "B.Fab")
		)
		(fp_line
			(start -0.3048 -0.1016)
			(end 0.3048 -0.1016)
			(stroke
				(width 0.1)
				(type default)
			)
			(layer "B.Fab")
		)
		(pad "1" smd rect
			(at 0 0)
			(size 0.508 0.508)
			(layers "B.Cu" "B.Mask" "B.Paste")
			(net "VCC_PA_3V3")
		)
		(pad "2" smd rect
			(at 0 0.889)
			(size 0.508 0.508)
			(layers "B.Cu" "B.Mask" "B.Paste")
			(net "GND")
		)
		(zone
			(layer "B.Cu")
			(hatch none 0.5)
			(connect_pads
				(clearance 0)
			)
			(min_thickness 0.25)
			(keepout
				(tracks not_allowed)
				(vias allowed)
				(pads allowed)
				(copperpour not_allowed)
				(footprints allowed)
			)
			(placement
				(enabled no)
				(sheetname "")
			)
			(fill
				(thermal_gap 0.5)
				(thermal_bridge_width 0.5)
				(island_removal_mode 0)
			)
			(polygon
				(pts
					(xy 423.133774 -41.617646) (xy 423.641774 -41.617646) (xy 423.641774 -41.236646) (xy 423.133774 -41.236646)
				)
			)
		)
		(zone
			(layer "B.Cu")
			(hatch none 0.5)
			(connect_pads
				(clearance 0)
			)
			(min_thickness 0.25)
			(keepout
				(tracks allowed)
				(vias not_allowed)
				(pads allowed)
				(copperpour not_allowed)
				(footprints allowed)
			)
			(placement
				(enabled no)
				(sheetname "")
			)
			(fill
				(thermal_gap 0.5)
				(thermal_bridge_width 0.5)
				(island_removal_mode 0)
			)
			(polygon
				(pts
					(xy 423.133774 -41.236646) (xy 423.641774 -41.236646) (xy 423.641774 -41.617646) (xy 423.133774 -41.617646)
				)
			)
		)
	)
	(footprint ""
		(layer "B.Cu")
		(at 370.986558 -40.617648 90)
		(property "Reference" "R2T57"
			(at 0 0 90)
			(layer "B.SilkS")
			(hide yes)
			(effects
				(font
					(size 1.27 1.27)
				)
				(justify mirror)
			)
		)
		(property "Value" ""
			(at 0 0 90)
			(layer "B.Fab")
			(effects
				(font
					(size 1.27 1.27)
				)
				(justify mirror)
			)
		)
		(duplicate_pad_numbers_are_jumpers no)
		(fp_poly
			(pts
				(xy 0.2794 -0.1016) (xy -0.2794 -0.1016) (xy -0.2794 0.9906) (xy 0.2794 0.9906)
			)
			(stroke
				(width 0)
				(type default)
			)
			(fill no)
			(layer "B.CrtYd")
		)
		(fp_line
			(start 0.2794 -0.1016)
			(end 0.2794 0.9906)
			(stroke
				(width 0.1)
				(type default)
			)
			(layer "B.Fab")
		)
		(fp_line
			(start -0.2794 -0.1016)
			(end 0.2794 -0.1016)
			(stroke
				(width 0.1)
				(type default)
			)
			(layer "B.Fab")
		)
		(fp_line
			(start 0.2794 0.9906)
			(end -0.2794 0.9906)
			(stroke
				(width 0.1)
				(type default)
			)
			(layer "B.Fab")
		)
		(fp_line
			(start -0.2794 0.9906)
			(end -0.2794 -0.1016)
			(stroke
				(width 0.1)
				(type default)
			)
			(layer "B.Fab")
		)
		(pad "1" smd rect
			(at 0 0 270)
			(size 0.508 0.508)
			(layers "B.Cu" "B.Mask" "B.Paste")
			(net "H_CPU_ERR0_PCH_N")
		)
		(pad "2" smd rect
			(at 0 0.889 270)
			(size 0.508 0.508)
			(layers "B.Cu" "B.Mask" "B.Paste")
			(net "H_CPU_ERR0_GTL_R_N")
		)
		(zone
			(layer "B.Cu")
			(hatch none 0.5)
			(connect_pads
				(clearance 0)
			)
			(min_thickness 0.25)
			(keepout
				(tracks allowed)
				(vias not_allowed)
				(pads allowed)
				(copperpour not_allowed)
				(footprints allowed)
			)
			(placement
				(enabled no)
				(sheetname "")
			)
			(fill
				(thermal_gap 0.5)
				(thermal_bridge_width 0.5)
				(island_removal_mode 0)
			)
			(polygon
				(pts
					(xy 371.240558 -40.871648) (xy 371.240558 -40.363648) (xy 371.621558 -40.363648) (xy 371.621558 -40.871648)
				)
			)
		)
		(zone
			(layer "B.Cu")
			(hatch none 0.5)
			(connect_pads
				(clearance 0)
			)
			(min_thickness 0.25)
			(keepout
				(tracks not_allowed)
				(vias allowed)
				(pads allowed)
				(copperpour not_allowed)
				(footprints allowed)
			)
			(placement
				(enabled no)
				(sheetname "")
			)
			(fill
				(thermal_gap 0.5)
				(thermal_bridge_width 0.5)
				(island_removal_mode 0)
			)
			(polygon
				(pts
					(xy 371.621558 -40.871648) (xy 371.621558 -40.363648) (xy 371.240558 -40.363648) (xy 371.240558 -40.871648)
				)
			)
		)
	)
)
